(kicad_pcb
	(version 20260206)
	(generator "pcbnew")
	(generator_version "10.0")
	(general
		(thickness 1.6)
		(legacy_teardrops no)
	)
	(paper "A4")
	(title_block
		(title "Bryce Canyon_R.DPB_16317-1_OCP.brd")
		(comment 1 "Bryce Canyon / footprints 1135-1141 of 2099")
	)
	(layers
		(0 "F.Cu" signal "TOP")
		(4 "In1.Cu" signal "L2GND")
		(6 "In2.Cu" signal "L3")
		(8 "In3.Cu" signal "L4VCC")
		(10 "In4.Cu" signal "L5VCC")
		(12 "In5.Cu" signal "L6")
		(14 "In6.Cu" signal "L7GND")
		(2 "B.Cu" signal "BOTTOM")
		(9 "F.Adhes" user "F.Adhesive")
		(11 "B.Adhes" user "B.Adhesive")
		(13 "F.Paste" user "Package Geometry/Pastemask Top")
		(15 "B.Paste" user "Package Geometry/Pastemask Bottom")
		(5 "F.SilkS" user "Ref Des/Silkscreen Top")
		(7 "B.SilkS" user "Ref Des/Silkscreen Bottom")
		(1 "F.Mask" user "Board Geometry/Soldermask Top")
		(3 "B.Mask" user "Board Geometry/Soldermask Bottom")
		(17 "Dwgs.User" user "User.Drawings")
		(19 "Cmts.User" user "User.Comments")
		(21 "Eco1.User" user "User.Eco1")
		(23 "Eco2.User" user "User.Eco2")
		(25 "Edge.Cuts" user "Board Geometry/Outline")
		(27 "Margin" user)
		(31 "F.CrtYd" user "Package Geometry/Place Bound Top")
		(29 "B.CrtYd" user "Package Geometry/Place Bound Bottom")
		(35 "F.Fab" user "Ref Des/Assembly Top")
		(33 "B.Fab" user "Ref Des/Assembly Bottom")
	)
	(footprint ""
		(layer "F.Cu")
		(at 396.621 -44.958 180)
		(property "Reference" "C451"
			(at 0 0 180)
			(layer "F.SilkS")
			(hide yes)
			(effects
				(font
					(size 1.27 1.27)
				)
			)
		)
		(property "Value" "SC4D7U25V5KX-1-GP"
			(at -0.0762 -6.1214 180)
			(unlocked yes)
			(layer "F.Fab")
			(hide yes)
			(effects
				(font
					(size 1.016 1.016)
					(thickness 0.1524)
				)
			)
		)
		(property "Device Type" "C805H58"
			(at -0.0762 -8.1534 180)
			(unlocked yes)
			(layer "F.Fab")
			(hide yes)
			(effects
				(font
					(size 1.016 1.016)
					(thickness 0.1524)
				)
			)
		)
		(duplicate_pad_numbers_are_jumpers no)
		(fp_line
			(start 0.635 0)
			(end -0.635 0)
			(stroke
				(width 0.508)
				(type default)
			)
			(layer "F.SilkS")
		)
		(fp_rect
			(start -0.9652 1.778)
			(end 0.9652 -1.778)
			(stroke
				(width 0)
				(type default)
			)
			(fill no)
			(layer "F.CrtYd")
		)
		(fp_poly
			(pts
				(xy -0.9652 -1.778) (xy 0.9652 -1.778) (xy 0.9652 1.778) (xy -0.9652 1.778)
			)
			(stroke
				(width 0)
				(type default)
			)
			(fill no)
			(layer "F.Fab")
		)
		(pad "1" smd rect
			(at 0 -0.9652 180)
			(size 1.397 1.143)
			(layers "F.Cu" "F.Mask" "F.Paste")
			(net "P12V_HDD32")
		)
		(pad "2" smd rect
			(at 0 0.9652 180)
			(size 1.397 1.143)
			(layers "F.Cu" "F.Mask" "F.Paste")
			(net "GND")
		)
	)
	(footprint ""
		(layer "F.Cu")
		(at 18.415 -16.637)
		(property "Reference" "R639"
			(at 0 0 0)
			(layer "F.SilkS")
			(hide yes)
			(effects
				(font
					(size 1.27 1.27)
				)
			)
		)
		(property "Value" "0R2J-2-GP"
			(at 0.064008 -3.993896 0)
			(unlocked yes)
			(layer "F.Fab")
			(hide yes)
			(effects
				(font
					(size 1.016 1.016)
					(thickness 0.1524)
				)
			)
		)
		(property "Device Type" "R402H16"
			(at 0.064008 -5.517896 0)
			(unlocked yes)
			(layer "F.Fab")
			(hide yes)
			(effects
				(font
					(size 1.016 1.016)
					(thickness 0.1524)
				)
			)
		)
		(duplicate_pad_numbers_are_jumpers no)
		(fp_line
			(start -0.508 -0.9398)
			(end -0.508 0.9398)
			(stroke
				(width 0.1524)
				(type default)
			)
			(layer "F.SilkS")
		)
		(fp_line
			(start 0.508 -0.9398)
			(end -0.508 -0.9398)
			(stroke
				(width 0.1524)
				(type default)
			)
			(layer "F.SilkS")
		)
		(fp_rect
			(start -0.508 0.9398)
			(end 0.508 -0.9398)
			(stroke
				(width 0)
				(type default)
			)
			(fill no)
			(layer "F.CrtYd")
		)
		(fp_rect
			(start -0.508 0.9398)
			(end 0.508 -0.9398)
			(stroke
				(width 0)
				(type default)
			)
			(fill no)
			(layer "F.Fab")
		)
		(pad "1" smd custom
			(at 0 -0.4445)
			(size 0.1397 0.1397)
			(layers "F.Cu" "F.Mask" "F.Paste")
			(net "SW_HDD_G24")
			(options
				(clearance outline)
				(anchor circle)
			)
			(primitives
				(gr_poly
					(pts
						(arc
							(start -0.1778 -0.2794)
							(mid -0.249642 -0.249642)
							(end -0.2794 -0.1778)
						)
						(arc
							(start -0.2794 0.1778)
							(mid -0.249642 0.249642)
							(end -0.1778 0.2794)
						)
						(arc
							(start 0.1778 0.2794)
							(mid 0.249642 0.249642)
							(end 0.2794 0.1778)
						)
						(arc
							(start 0.2794 -0.1778)
							(mid 0.249642 -0.249642)
							(end 0.1778 -0.2794)
						)
					)
					(width 0)
					(fill yes)
				)
			)
		)
		(pad "2" smd custom
			(at 0 0.4445)
			(size 0.1397 0.1397)
			(layers "F.Cu" "F.Mask" "F.Paste")
			(net "SW_HDD_R24")
			(options
				(clearance outline)
				(anchor circle)
			)
			(primitives
				(gr_poly
					(pts
						(arc
							(start -0.1778 -0.2794)
							(mid -0.249642 -0.249642)
							(end -0.2794 -0.1778)
						)
						(arc
							(start -0.2794 0.1778)
							(mid -0.249642 0.249642)
							(end -0.1778 0.2794)
						)
						(arc
							(start 0.1778 0.2794)
							(mid 0.249642 0.249642)
							(end 0.2794 0.1778)
						)
						(arc
							(start 0.2794 -0.1778)
							(mid 0.249642 -0.249642)
							(end 0.1778 -0.2794)
						)
					)
					(width 0)
					(fill yes)
				)
			)
		)
	)
	(footprint ""
		(layer "F.Cu")
		(at 343.454228 -214.757 180)
		(property "Reference" "Q226"
			(at 0 0 180)
			(layer "F.SilkS")
			(hide yes)
			(effects
				(font
					(size 1.27 1.27)
				)
			)
		)
		(property "Value" "2N7002K-2-GP"
			(at 0.127 -8.9662 180)
			(unlocked yes)
			(layer "F.Fab")
			(hide yes)
			(effects
				(font
					(size 1.016 1.016)
					(thickness 0.1524)
				)
			)
		)
		(property "Device Type" "SOT23DGS2D4H44"
			(at 0.127 -10.4902 180)
			(unlocked yes)
			(layer "F.Fab")
			(hide yes)
			(effects
				(font
					(size 1.016 1.016)
					(thickness 0.1524)
				)
			)
		)
		(duplicate_pad_numbers_are_jumpers no)
		(fp_line
			(start 1.651 1.778)
			(end 1.651 -1.778)
			(stroke
				(width 0.1524)
				(type default)
			)
			(layer "F.SilkS")
		)
		(fp_line
			(start 1.651 -1.778)
			(end -1.651 -1.778)
			(stroke
				(width 0.1524)
				(type default)
			)
			(layer "F.SilkS")
		)
		(fp_line
			(start -1.651 1.778)
			(end 1.651 1.778)
			(stroke
				(width 0.1524)
				(type default)
			)
			(layer "F.SilkS")
		)
		(fp_line
			(start -1.651 -1.778)
			(end -1.651 1.778)
			(stroke
				(width 0.1524)
				(type default)
			)
			(layer "F.SilkS")
		)
		(fp_poly
			(pts
				(xy -1.778 1.8796) (xy -1.778 -1.8796) (xy 1.778 -1.8796) (xy 1.778 1.8796)
			)
			(stroke
				(width 0)
				(type default)
			)
			(fill no)
			(layer "F.CrtYd")
		)
		(fp_poly
			(pts
				(xy -1.778 1.8796) (xy -1.778 -1.8796) (xy 1.778 -1.8796) (xy 1.778 1.8796)
			)
			(stroke
				(width 0)
				(type default)
			)
			(fill no)
			(layer "F.Fab")
		)
		(pad "D" smd custom
			(at 0 -0.9525 180)
			(size 0.1905 0.1905)
			(layers "F.Cu" "F.Mask" "F.Paste")
			(net "FLT_HDD7_N")
			(options
				(clearance outline)
				(anchor circle)
			)
			(primitives
				(gr_poly
					(pts
						(arc
							(start -0.1778 0.5715)
							(mid -0.321484 0.511984)
							(end -0.381 0.3683)
						)
						(arc
							(start -0.381 -0.3683)
							(mid -0.321484 -0.511984)
							(end -0.1778 -0.5715)
						)
						(arc
							(start 0.1778 -0.5715)
							(mid 0.321484 -0.511984)
							(end 0.381 -0.3683)
						)
						(arc
							(start 0.381 0.3683)
							(mid 0.321484 0.511984)
							(end 0.1778 0.5715)
						)
					)
					(width 0)
					(fill yes)
				)
			)
		)
		(pad "G" smd custom
			(at -0.98425 0.9525 180)
			(size 0.1905 0.1905)
			(layers "F.Cu" "F.Mask" "F.Paste")
			(net "DRIVE_B_7_FLT_LED")
			(options
				(clearance outline)
				(anchor circle)
			)
			(primitives
				(gr_poly
					(pts
						(arc
							(start -0.1778 0.5715)
							(mid -0.321484 0.511984)
							(end -0.381 0.3683)
						)
						(arc
							(start -0.381 -0.3683)
							(mid -0.321484 -0.511984)
							(end -0.1778 -0.5715)
						)
						(arc
							(start 0.1778 -0.5715)
							(mid 0.321484 -0.511984)
							(end 0.381 -0.3683)
						)
						(arc
							(start 0.381 0.3683)
							(mid 0.321484 0.511984)
							(end 0.1778 0.5715)
						)
					)
					(width 0)
					(fill yes)
				)
			)
		)
		(pad "S" smd custom
			(at 0.98425 0.9525 180)
			(size 0.1905 0.1905)
			(layers "F.Cu" "F.Mask" "F.Paste")
			(net "GND")
			(options
				(clearance outline)
				(anchor circle)
			)
			(primitives
				(gr_poly
					(pts
						(arc
							(start -0.1778 0.5715)
							(mid -0.321484 0.511984)
							(end -0.381 0.3683)
						)
						(arc
							(start -0.381 -0.3683)
							(mid -0.321484 -0.511984)
							(end -0.1778 -0.5715)
						)
						(arc
							(start 0.1778 -0.5715)
							(mid 0.321484 -0.511984)
							(end 0.381 -0.3683)
						)
						(arc
							(start 0.381 0.3683)
							(mid 0.321484 0.511984)
							(end 0.1778 0.5715)
						)
					)
					(width 0)
					(fill yes)
				)
			)
		)
	)
	(footprint ""
		(layer "F.Cu")
		(at 463.423 -248.793 90)
		(property "Reference" "D10"
			(at 0 0 90)
			(layer "F.SilkS")
			(hide yes)
			(effects
				(font
					(size 1.27 1.27)
				)
			)
		)
		(property "Value" "RB551V30-GP"
			(at 0 -6.7818 90)
			(unlocked yes)
			(layer "F.Fab")
			(hide yes)
			(effects
				(font
					(size 1.016 1.016)
					(thickness 0.1524)
				)
			)
		)
		(property "Device Type" "SOD323AKH38"
			(at 0 -8.6868 90)
			(unlocked yes)
			(layer "F.Fab")
			(hide yes)
			(effects
				(font
					(size 1.016 1.016)
					(thickness 0.1524)
				)
			)
		)
		(duplicate_pad_numbers_are_jumpers no)
		(fp_line
			(start 0.889 -1.9304)
			(end 0.889 2.159)
			(stroke
				(width 0.1524)
				(type default)
			)
			(layer "F.SilkS")
		)
		(fp_line
			(start -0.889 -1.9304)
			(end 0.889 -1.9304)
			(stroke
				(width 0.1524)
				(type default)
			)
			(layer "F.SilkS")
		)
		(fp_line
			(start 0.762 2.0574)
			(end -0.762 2.0574)
			(stroke
				(width 0.508)
				(type default)
			)
			(layer "F.SilkS")
		)
		(fp_line
			(start 0.889 2.159)
			(end -0.889 2.159)
			(stroke
				(width 0.1524)
				(type default)
			)
			(layer "F.SilkS")
		)
		(fp_line
			(start -0.889 2.159)
			(end -0.889 -1.9304)
			(stroke
				(width 0.1524)
				(type default)
			)
			(layer "F.SilkS")
		)
		(fp_rect
			(start -1.016 2.3114)
			(end 1.016 -2.0066)
			(stroke
				(width 0)
				(type default)
			)
			(fill no)
			(layer "F.CrtYd")
		)
		(fp_poly
			(pts
				(xy -1.016 -2.0066) (xy 1.016 -2.0066) (xy 1.016 2.3114) (xy -1.016 2.3114)
			)
			(stroke
				(width 0)
				(type default)
			)
			(fill no)
			(layer "F.Fab")
		)
		(pad "A" smd rect
			(at 0 -1.143 90)
			(size 0.5588 1.016)
			(layers "F.Cu" "F.Mask" "F.Paste")
			(net "SW_HDD_R10")
		)
		(pad "K" smd rect
			(at 0 1.143 90)
			(size 0.5588 1.016)
			(layers "F.Cu" "F.Mask" "F.Paste")
			(net "SW_HDD_N10")
		)
	)
	(footprint ""
		(layer "F.Cu")
		(at 221.996 -224.282 90)
		(property "Reference" "R21"
			(at 0 0 90)
			(layer "F.SilkS")
			(hide yes)
			(effects
				(font
					(size 1.27 1.27)
				)
			)
		)
		(property "Value" "0R2J-2-GP"
			(at 0.064008 -3.993896 90)
			(unlocked yes)
			(layer "F.Fab")
			(hide yes)
			(effects
				(font
					(size 1.016 1.016)
					(thickness 0.1524)
				)
			)
		)
		(property "Device Type" "R402H16"
			(at 0.064008 -5.517896 90)
			(unlocked yes)
			(layer "F.Fab")
			(hide yes)
			(effects
				(font
					(size 1.016 1.016)
					(thickness 0.1524)
				)
			)
		)
		(duplicate_pad_numbers_are_jumpers no)
		(fp_line
			(start 0.508 -0.9398)
			(end -0.508 -0.9398)
			(stroke
				(width 0.1524)
				(type default)
			)
			(layer "F.SilkS")
		)
		(fp_line
			(start -0.508 -0.9398)
			(end -0.508 0.9398)
			(stroke
				(width 0.1524)
				(type default)
			)
			(layer "F.SilkS")
		)
		(fp_rect
			(start -0.508 0.9398)
			(end 0.508 -0.9398)
			(stroke
				(width 0)
				(type default)
			)
			(fill no)
			(layer "F.CrtYd")
		)
		(fp_rect
			(start -0.508 0.9398)
			(end 0.508 -0.9398)
			(stroke
				(width 0)
				(type default)
			)
			(fill no)
			(layer "F.Fab")
		)
		(pad "1" smd custom
			(at 0 -0.4445 90)
			(size 0.1397 0.1397)
			(layers "F.Cu" "F.Mask" "F.Paste")
			(net "IO_EXP1_LED_SDA")
			(options
				(clearance outline)
				(anchor circle)
			)
			(primitives
				(gr_poly
					(pts
						(arc
							(start -0.1778 -0.2794)
							(mid -0.249642 -0.249642)
							(end -0.2794 -0.1778)
						)
						(arc
							(start -0.2794 0.1778)
							(mid -0.249642 0.249642)
							(end -0.1778 0.2794)
						)
						(arc
							(start 0.1778 0.2794)
							(mid 0.249642 0.249642)
							(end 0.2794 0.1778)
						)
						(arc
							(start 0.2794 -0.1778)
							(mid 0.249642 -0.249642)
							(end 0.1778 -0.2794)
						)
					)
					(width 0)
					(fill yes)
				)
			)
		)
		(pad "2" smd custom
			(at 0 0.4445 90)
			(size 0.1397 0.1397)
			(layers "F.Cu" "F.Mask" "F.Paste")
			(net "I2C_DRIVE_B_FLT_LED_SDA")
			(options
				(clearance outline)
				(anchor circle)
			)
			(primitives
				(gr_poly
					(pts
						(arc
							(start -0.1778 -0.2794)
							(mid -0.249642 -0.249642)
							(end -0.2794 -0.1778)
						)
						(arc
							(start -0.2794 0.1778)
							(mid -0.249642 0.249642)
							(end -0.1778 0.2794)
						)
						(arc
							(start 0.1778 0.2794)
							(mid 0.249642 0.249642)
							(end 0.2794 0.1778)
						)
						(arc
							(start 0.2794 -0.1778)
							(mid 0.249642 -0.249642)
							(end 0.1778 -0.2794)
						)
					)
					(width 0)
					(fill yes)
				)
			)
		)
	)
	(footprint ""
		(layer "F.Cu")
		(at 79.883 -253.111 90)
		(property "Reference" "R195"
			(at 0 0 90)
			(layer "F.SilkS")
			(hide yes)
			(effects
				(font
					(size 1.27 1.27)
				)
			)
		)
		(property "Value" "4K7R2J-2-GP"
			(at 0.064008 -3.993896 90)
			(unlocked yes)
			(layer "F.Fab")
			(hide yes)
			(effects
				(font
					(size 1.016 1.016)
					(thickness 0.1524)
				)
			)
		)
		(property "Device Type" "R402H16"
			(at 0.064008 -5.517896 90)
			(unlocked yes)
			(layer "F.Fab")
			(hide yes)
			(effects
				(font
					(size 1.016 1.016)
					(thickness 0.1524)
				)
			)
		)
		(duplicate_pad_numbers_are_jumpers no)
		(fp_line
			(start 0.508 -0.9398)
			(end -0.508 -0.9398)
			(stroke
				(width 0.1524)
				(type default)
			)
			(layer "F.SilkS")
		)
		(fp_line
			(start -0.508 -0.9398)
			(end -0.508 0.9398)
			(stroke
				(width 0.1524)
				(type default)
			)
			(layer "F.SilkS")
		)
		(fp_rect
			(start -0.508 0.9398)
			(end 0.508 -0.9398)
			(stroke
				(width 0)
				(type default)
			)
			(fill no)
			(layer "F.CrtYd")
		)
		(fp_rect
			(start -0.508 0.9398)
			(end 0.508 -0.9398)
			(stroke
				(width 0)
				(type default)
			)
			(fill no)
			(layer "F.Fab")
		)
		(pad "1" smd custom
			(at 0 -0.4445 90)
			(size 0.1397 0.1397)
			(layers "F.Cu" "F.Mask" "F.Paste")
			(net "P12V_B")
			(options
				(clearance outline)
				(anchor circle)
			)
			(primitives
				(gr_poly
					(pts
						(arc
							(start -0.1778 -0.2794)
							(mid -0.249642 -0.249642)
							(end -0.2794 -0.1778)
						)
						(arc
							(start -0.2794 0.1778)
							(mid -0.249642 0.249642)
							(end -0.1778 0.2794)
						)
						(arc
							(start 0.1778 0.2794)
							(mid 0.249642 0.249642)
							(end 0.2794 0.1778)
						)
						(arc
							(start 0.2794 -0.1778)
							(mid 0.249642 -0.249642)
							(end 0.1778 -0.2794)
						)
					)
					(width 0)
					(fill yes)
				)
			)
		)
		(pad "2" smd custom
			(at 0 0.4445 90)
			(size 0.1397 0.1397)
			(layers "F.Cu" "F.Mask" "F.Paste")
			(net "SW_HDD_P2")
			(options
				(clearance outline)
				(anchor circle)
			)
			(primitives
				(gr_poly
					(pts
						(arc
							(start -0.1778 -0.2794)
							(mid -0.249642 -0.249642)
							(end -0.2794 -0.1778)
						)
						(arc
							(start -0.2794 0.1778)
							(mid -0.249642 0.249642)
							(end -0.1778 0.2794)
						)
						(arc
							(start 0.1778 0.2794)
							(mid 0.249642 0.249642)
							(end 0.2794 0.1778)
						)
						(arc
							(start 0.2794 -0.1778)
							(mid 0.249642 -0.249642)
							(end 0.1778 -0.2794)
						)
					)
					(width 0)
					(fill yes)
				)
			)
		)
	)
	(footprint ""
		(layer "F.Cu")
		(at 448.538854 -102.184454 -90)
		(property "Reference" "R482"
			(at 0 0 270)
			(layer "F.SilkS")
			(hide yes)
			(effects
				(font
					(size 1.27 1.27)
				)
			)
		)
		(property "Value" "4K7R2F-GP"
			(at 0.064008 -3.993896 270)
			(unlocked yes)
			(layer "F.Fab")
			(hide yes)
			(effects
				(font
					(size 1.016 1.016)
					(thickness 0.1524)
				)
			)
		)
		(property "Device Type" "R402H16"
			(at 0.064008 -5.517896 270)
			(unlocked yes)
			(layer "F.Fab")
			(hide yes)
			(effects
				(font
					(size 1.016 1.016)
					(thickness 0.1524)
				)
			)
		)
		(duplicate_pad_numbers_are_jumpers no)
		(fp_line
			(start -0.508 -0.9398)
			(end -0.508 0.9398)
			(stroke
				(width 0.1524)
				(type default)
			)
			(layer "F.SilkS")
		)
		(fp_line
			(start 0.508 -0.9398)
			(end -0.508 -0.9398)
			(stroke
				(width 0.1524)
				(type default)
			)
			(layer "F.SilkS")
		)
		(fp_rect
			(start -0.508 0.9398)
			(end 0.508 -0.9398)
			(stroke
				(width 0)
				(type default)
			)
			(fill no)
			(layer "F.CrtYd")
		)
		(fp_rect
			(start -0.508 0.9398)
			(end 0.508 -0.9398)
			(stroke
				(width 0)
				(type default)
			)
			(fill no)
			(layer "F.Fab")
		)
		(pad "1" smd custom
			(at 0 -0.4445 270)
			(size 0.1397 0.1397)
			(layers "F.Cu" "F.Mask" "F.Paste")
			(net "DRIVE_B_22_FLT_LED")
			(options
				(clearance outline)
				(anchor circle)
			)
			(primitives
				(gr_poly
					(pts
						(arc
							(start -0.1778 -0.2794)
							(mid -0.249642 -0.249642)
							(end -0.2794 -0.1778)
						)
						(arc
							(start -0.2794 0.1778)
							(mid -0.249642 0.249642)
							(end -0.1778 0.2794)
						)
						(arc
							(start 0.1778 0.2794)
							(mid 0.249642 0.249642)
							(end 0.2794 0.1778)
						)
						(arc
							(start 0.2794 -0.1778)
							(mid 0.249642 -0.249642)
							(end 0.1778 -0.2794)
						)
					)
					(width 0)
					(fill yes)
				)
			)
		)
		(pad "2" smd custom
			(at 0 0.4445 270)
			(size 0.1397 0.1397)
			(layers "F.Cu" "F.Mask" "F.Paste")
			(net "GND")
			(options
				(clearance outline)
				(anchor circle)
			)
			(primitives
				(gr_poly
					(pts
						(arc
							(start -0.1778 -0.2794)
							(mid -0.249642 -0.249642)
							(end -0.2794 -0.1778)
						)
						(arc
							(start -0.2794 0.1778)
							(mid -0.249642 0.249642)
							(end -0.1778 0.2794)
						)
						(arc
							(start 0.1778 0.2794)
							(mid 0.249642 0.249642)
							(end 0.2794 0.1778)
						)
						(arc
							(start 0.2794 -0.1778)
							(mid 0.249642 -0.249642)
							(end 0.1778 -0.2794)
						)
					)
					(width 0)
					(fill yes)
				)
			)
		)
	)
)
